(kicad_pcb
	(version 20260206)
	(generator "pcbnew")
	(generator_version "10.0")
	(general
		(thickness 1.6)
		(legacy_teardrops no)
	)
	(paper "A4")
	(title_block
		(title "v1-chassis-manager — T6M_CM_d_v01_1031_1645.brd")
		(comment 1 "Open CloudServer (Microsoft) / footprints 560-568 of 2512")
	)
	(layers
		(0 "F.Cu" signal "TOP")
		(4 "In1.Cu" signal "GND1")
		(6 "In2.Cu" signal "IN1")
		(8 "In3.Cu" signal "VCC1")
		(10 "In4.Cu" signal "VCC2")
		(12 "In5.Cu" signal "GND2")
		(14 "In6.Cu" signal "IN2")
		(16 "In7.Cu" signal "IN3")
		(18 "In8.Cu" signal "GND3")
		(2 "B.Cu" signal "BOTTOM")
		(9 "F.Adhes" user "F.Adhesive")
		(11 "B.Adhes" user "B.Adhesive")
		(13 "F.Paste" user "Package Geometry/Pastemask Top")
		(15 "B.Paste" user "Package Geometry/Pastemask Bottom")
		(5 "F.SilkS" user "Ref Des/Silkscreen Top")
		(7 "B.SilkS" user "Ref Des/Silkscreen Bottom")
		(1 "F.Mask" user "Board Geometry/Soldermask Top")
		(3 "B.Mask" user "Board Geometry/Soldermask Bottom")
		(17 "Dwgs.User" user "User.Drawings")
		(19 "Cmts.User" user "User.Comments")
		(21 "Eco1.User" user "User.Eco1")
		(23 "Eco2.User" user "User.Eco2")
		(25 "Edge.Cuts" user "Board Geometry/Outline")
		(27 "Margin" user)
		(31 "F.CrtYd" user "Package Geometry/Place Bound Top")
		(29 "B.CrtYd" user "Package Geometry/Place Bound Bottom")
		(35 "F.Fab" user "Ref Des/Assembly Top")
		(33 "B.Fab" user "Ref Des/Assembly Bottom")
	)
	(footprint ""
		(layer "F.Cu")
		(at 35.013138 -170.551856 -90)
		(property "Reference" "U109"
			(at 6.111748 1.307338 0)
			(unlocked yes)
			(layer "F.SilkS")
			(effects
				(font
					(size 0.7874 0.5842)
					(thickness 0.1524)
				)
			)
		)
		(property "Value" ""
			(at 0 0 270)
			(layer "F.Fab")
			(effects
				(font
					(size 1.27 1.27)
				)
			)
		)
		(duplicate_pad_numbers_are_jumpers no)
		(fp_line
			(start -1.651 1.905)
			(end -1.651 -1.905)
			(stroke
				(width 0.1524)
				(type default)
			)
			(layer "F.SilkS")
		)
		(fp_line
			(start 1.651 1.905)
			(end -1.651 1.905)
			(stroke
				(width 0.1524)
				(type default)
			)
			(layer "F.SilkS")
		)
		(fp_line
			(start -1.651 -1.905)
			(end 1.651 -1.905)
			(stroke
				(width 0.1524)
				(type default)
			)
			(layer "F.SilkS")
		)
		(fp_line
			(start 1.651 -1.905)
			(end 1.651 1.905)
			(stroke
				(width 0.1524)
				(type default)
			)
			(layer "F.SilkS")
		)
		(fp_poly
			(pts
				(xy -1.524 0.7112) (xy -1.524 1.7526) (xy -0.508 1.7526) (xy -0.508 0.6985) (xy 0.508 0.6985) (xy 0.508 1.7526)
				(xy 1.524 1.7526) (xy 1.524 0.6985) (xy 1.524 -0.6985) (xy 0.508 -0.6985) (xy 0.508 -1.7526) (xy -0.508 -1.7526)
				(xy -0.508 -0.6985) (xy -1.524 -0.6985) (xy -1.524 0.6985)
			)
			(stroke
				(width 0)
				(type default)
			)
			(fill no)
			(layer "F.CrtYd")
		)
		(fp_text user "G"
			(at -2.298192 1.322578 0)
			(unlocked yes)
			(layer "F.SilkS")
			(effects
				(font
					(size 0.7874 0.5842)
					(thickness 0.1524)
				)
			)
		)
		(fp_text user "S"
			(at 2.322068 0.692658 0)
			(unlocked yes)
			(layer "F.SilkS")
			(effects
				(font
					(size 0.7874 0.5842)
					(thickness 0.1524)
				)
			)
		)
		(fp_text user "D"
			(at -0.318262 -2.54127 0)
			(unlocked yes)
			(layer "F.SilkS")
			(effects
				(font
					(size 0.7874 0.5842)
					(thickness 0.1524)
				)
			)
		)
		(pad "D" smd rect
			(at 0 -1.1176 270)
			(size 1.016 1.27)
			(layers "F.Cu" "F.Mask" "F.Paste")
			(net "P12V_AUX_EN")
		)
		(pad "G" smd rect
			(at -1.016 1.1176 270)
			(size 1.016 1.27)
			(layers "F.Cu" "F.Mask" "F.Paste")
			(net "CM_PWR_CTL_IN_R")
		)
		(pad "S" smd rect
			(at 1.016 1.1176 270)
			(size 1.016 1.27)
			(layers "F.Cu" "F.Mask" "F.Paste")
			(net "GND")
		)
	)
	(footprint ""
		(layer "F.Cu")
		(at 154.638502 -129.314448)
		(property "Reference" "S3"
			(at -3.178302 4.244848 0)
			(unlocked yes)
			(layer "F.SilkS")
			(effects
				(font
					(size 0.7874 0.5842)
					(thickness 0.1524)
				)
				(justify left)
			)
		)
		(property "Value" ""
			(at 0 0 0)
			(layer "F.Fab")
			(effects
				(font
					(size 1.27 1.27)
				)
			)
		)
		(duplicate_pad_numbers_are_jumpers no)
		(fp_line
			(start -3.0988 -3.0988)
			(end 3.0988 -3.0988)
			(stroke
				(width 0.1524)
				(type default)
			)
			(layer "F.SilkS")
		)
		(fp_line
			(start -3.0988 -2.667)
			(end -3.0988 -3.0988)
			(stroke
				(width 0.1524)
				(type default)
			)
			(layer "F.SilkS")
		)
		(fp_line
			(start -3.0988 -1.3462)
			(end -3.0988 1.3208)
			(stroke
				(width 0.1524)
				(type default)
			)
			(layer "F.SilkS")
		)
		(fp_line
			(start -3.0988 2.6416)
			(end -3.0988 3.0988)
			(stroke
				(width 0.1524)
				(type default)
			)
			(layer "F.SilkS")
		)
		(fp_line
			(start -3.0988 3.0988)
			(end 3.0988 3.0988)
			(stroke
				(width 0.1524)
				(type default)
			)
			(layer "F.SilkS")
		)
		(fp_line
			(start 3.0988 -3.0988)
			(end 3.0988 -2.667)
			(stroke
				(width 0.1524)
				(type default)
			)
			(layer "F.SilkS")
		)
		(fp_line
			(start 3.0988 1.3208)
			(end 3.0988 -1.3208)
			(stroke
				(width 0.1524)
				(type default)
			)
			(layer "F.SilkS")
		)
		(fp_line
			(start 3.0988 3.0988)
			(end 3.0988 2.667)
			(stroke
				(width 0.1524)
				(type default)
			)
			(layer "F.SilkS")
		)
		(fp_poly
			(pts
				(xy -4.797298 -2.696972) (xy -6.829298 -2.112772) (xy -6.829298 -3.408172)
			)
			(stroke
				(width 0)
				(type default)
			)
			(fill yes)
			(layer "F.SilkS")
		)
		(fp_poly
			(pts
				(xy -3.0988 3.0988) (xy -3.0988 2.5146) (xy -5.0038 2.5146) (xy -5.0038 1.4732) (xy -3.0988 1.4732)
				(xy -3.0988 -1.4986) (xy -5.0038 -1.4986) (xy -5.0038 -2.5146) (xy -3.0988 -2.5146) (xy -3.0988 -3.0988)
				(xy 3.0988 -3.0988) (xy 3.0988 -2.5146) (xy 5.0038 -2.5146) (xy 5.0038 -1.4732) (xy 3.0988 -1.4732)
				(xy 3.0988 1.4732) (xy 5.0038 1.4732) (xy 5.0038 2.5146) (xy 3.0988 2.5146) (xy 3.0988 3.0988)
			)
			(stroke
				(width 0)
				(type default)
			)
			(fill no)
			(layer "F.CrtYd")
		)
		(fp_text user "1"
			(at -4.618482 -0.670052 0)
			(unlocked yes)
			(layer "F.SilkS")
			(effects
				(font
					(size 0.635 0.4064)
					(thickness 0.1524)
				)
				(justify left)
			)
		)
		(fp_text user "3"
			(at -4.225036 3.265424 0)
			(unlocked yes)
			(layer "F.SilkS")
			(effects
				(font
					(size 0.635 0.4064)
					(thickness 0.1524)
				)
				(justify left)
			)
		)
		(fp_text user "4"
			(at 4.946904 0.843788 0)
			(unlocked yes)
			(layer "F.SilkS")
			(effects
				(font
					(size 0.635 0.4064)
					(thickness 0.1524)
				)
				(justify left)
			)
		)
		(fp_text user "2"
			(at 5.249672 -1.6383 0)
			(unlocked yes)
			(layer "F.SilkS")
			(effects
				(font
					(size 0.635 0.4064)
					(thickness 0.1524)
				)
				(justify left)
			)
		)
		(pad "1" smd rect
			(at -3.400044 -1.999996 90)
			(size 1.016 3.2004)
			(layers "F.Cu" "F.Mask" "F.Paste")
			(net "RST_BTN_L")
		)
		(pad "2" smd rect
			(at 3.400044 -1.999996 90)
			(size 1.016 3.2004)
			(layers "F.Cu" "F.Mask" "F.Paste")
			(net "RST_BTN_L")
		)
		(pad "3" smd rect
			(at -3.400044 1.999996 90)
			(size 1.016 3.2004)
			(layers "F.Cu" "F.Mask" "F.Paste")
			(net "GND")
		)
		(pad "4" smd rect
			(at 3.400044 1.999996 90)
			(size 1.016 3.2004)
			(layers "F.Cu" "F.Mask" "F.Paste")
			(net "GND")
		)
	)
	(footprint ""
		(layer "F.Cu")
		(at 134.22376 -185.205624 -90)
		(property "Reference" "R983"
			(at -4.510786 0.392938 90)
			(unlocked yes)
			(layer "F.SilkS")
			(effects
				(font
					(size 0.7874 0.5842)
					(thickness 0.1524)
				)
				(justify left)
			)
		)
		(property "Value" ""
			(at 0 0 270)
			(layer "F.Fab")
			(effects
				(font
					(size 1.27 1.27)
				)
			)
		)
		(duplicate_pad_numbers_are_jumpers no)
		(fp_line
			(start -0.7874 0.4064)
			(end -0.7874 -0.4064)
			(stroke
				(width 0.1524)
				(type default)
			)
			(layer "F.SilkS")
		)
		(fp_line
			(start 0.7874 0.4064)
			(end -0.7874 0.4064)
			(stroke
				(width 0.1524)
				(type default)
			)
			(layer "F.SilkS")
		)
		(fp_line
			(start -0.7874 -0.4064)
			(end 0.7874 -0.4064)
			(stroke
				(width 0.1524)
				(type default)
			)
			(layer "F.SilkS")
		)
		(fp_line
			(start 0.7874 -0.4064)
			(end 0.7874 0.4064)
			(stroke
				(width 0.1524)
				(type default)
			)
			(layer "F.SilkS")
		)
		(fp_poly
			(pts
				(xy -0.508 0.2794) (xy -0.508 0.2286) (xy -0.635 0.2286) (xy -0.635 -0.254) (xy -0.5334 -0.254)
				(xy -0.5334 -0.2794) (xy 0.5334 -0.2794) (xy 0.5334 -0.254) (xy 0.635 -0.254) (xy 0.635 0.254) (xy 0.5334 0.254)
				(xy 0.5334 0.2794)
			)
			(stroke
				(width 0)
				(type default)
			)
			(fill no)
			(layer "F.CrtYd")
		)
		(pad "1" smd rect
			(at 0.40005 0 270)
			(size 0.4572 0.508)
			(layers "F.Cu" "F.Mask" "F.Paste")
			(net "UART_T10_NODE1_TXD")
		)
		(pad "2" smd rect
			(at -0.40005 0 270)
			(size 0.4572 0.508)
			(layers "F.Cu" "F.Mask" "F.Paste")
			(net "UART_T10_NODE1_TXD_R")
		)
	)
	(footprint ""
		(layer "F.Cu")
		(at 113.90376 -185.205624 90)
		(property "Reference" "C760"
			(at 4.731512 -0.124968 90)
			(unlocked yes)
			(layer "F.SilkS")
			(effects
				(font
					(size 0.7874 0.5842)
					(thickness 0.1524)
				)
				(justify left)
			)
		)
		(property "Value" ""
			(at 0 0 90)
			(layer "F.Fab")
			(effects
				(font
					(size 1.27 1.27)
				)
			)
		)
		(duplicate_pad_numbers_are_jumpers no)
		(fp_line
			(start 0.7874 -0.4064)
			(end 0.7874 0.4064)
			(stroke
				(width 0.1524)
				(type default)
			)
			(layer "F.SilkS")
		)
		(fp_line
			(start -0.7874 -0.4064)
			(end 0.7874 -0.4064)
			(stroke
				(width 0.1524)
				(type default)
			)
			(layer "F.SilkS")
		)
		(fp_line
			(start 0 0.381)
			(end 0 -0.381)
			(stroke
				(width 0.1524)
				(type default)
			)
			(layer "F.SilkS")
		)
		(fp_line
			(start 0.7874 0.4064)
			(end -0.7874 0.4064)
			(stroke
				(width 0.1524)
				(type default)
			)
			(layer "F.SilkS")
		)
		(fp_line
			(start -0.7874 0.4064)
			(end -0.7874 -0.4064)
			(stroke
				(width 0.1524)
				(type default)
			)
			(layer "F.SilkS")
		)
		(fp_poly
			(pts
				(xy -0.5334 0.254) (xy -0.635 0.254) (xy -0.635 0.2286) (xy -0.635 -0.254) (xy -0.5334 -0.254) (xy -0.5334 -0.2794)
				(xy 0.5334 -0.2794) (xy 0.5334 -0.254) (xy 0.635 -0.254) (xy 0.635 0.254) (xy 0.5334 0.254) (xy 0.5334 0.2794)
				(xy -0.508 0.2794) (xy -0.5334 0.2794)
			)
			(stroke
				(width 0)
				(type default)
			)
			(fill no)
			(layer "F.CrtYd")
		)
		(pad "1" smd rect
			(at 0.40005 0 90)
			(size 0.4572 0.508)
			(layers "F.Cu" "F.Mask" "F.Paste")
			(net "UART_T8_NODE4_RXD")
		)
		(pad "2" smd rect
			(at -0.40005 0 90)
			(size 0.4572 0.508)
			(layers "F.Cu" "F.Mask" "F.Paste")
			(net "GND")
		)
	)
	(footprint ""
		(layer "F.Cu")
		(at 152.67051 -146.025362)
		(property "Reference" "C529"
			(at 1.873758 -1.693926 90)
			(unlocked yes)
			(layer "F.SilkS")
			(effects
				(font
					(size 0.635 0.4064)
					(thickness 0.1524)
				)
				(justify left)
			)
		)
		(property "Value" ""
			(at 0 0 0)
			(layer "F.Fab")
			(effects
				(font
					(size 1.27 1.27)
				)
			)
		)
		(duplicate_pad_numbers_are_jumpers no)
		(fp_line
			(start -0.7874 -0.4064)
			(end 0.7874 -0.4064)
			(stroke
				(width 0.1524)
				(type default)
			)
			(layer "F.SilkS")
		)
		(fp_line
			(start -0.7874 0.4064)
			(end -0.7874 -0.4064)
			(stroke
				(width 0.1524)
				(type default)
			)
			(layer "F.SilkS")
		)
		(fp_line
			(start 0 0.381)
			(end 0 -0.381)
			(stroke
				(width 0.1524)
				(type default)
			)
			(layer "F.SilkS")
		)
		(fp_line
			(start 0.7874 -0.4064)
			(end 0.7874 0.4064)
			(stroke
				(width 0.1524)
				(type default)
			)
			(layer "F.SilkS")
		)
		(fp_line
			(start 0.7874 0.4064)
			(end -0.7874 0.4064)
			(stroke
				(width 0.1524)
				(type default)
			)
			(layer "F.SilkS")
		)
		(fp_poly
			(pts
				(xy -0.5334 0.254) (xy -0.635 0.254) (xy -0.635 0.2286) (xy -0.635 -0.254) (xy -0.5334 -0.254) (xy -0.5334 -0.2794)
				(xy 0.5334 -0.2794) (xy 0.5334 -0.254) (xy 0.635 -0.254) (xy 0.635 0.254) (xy 0.5334 0.254) (xy 0.5334 0.2794)
				(xy -0.508 0.2794) (xy -0.5334 0.2794)
			)
			(stroke
				(width 0)
				(type default)
			)
			(fill no)
			(layer "F.CrtYd")
		)
		(pad "1" smd rect
			(at 0.40005 0)
			(size 0.4572 0.508)
			(layers "F.Cu" "F.Mask" "F.Paste")
			(net "LAN2_LED_LINK_1000_N")
		)
		(pad "2" smd rect
			(at -0.40005 0)
			(size 0.4572 0.508)
			(layers "F.Cu" "F.Mask" "F.Paste")
			(net "GND")
		)
	)
	(footprint ""
		(layer "F.Cu")
		(at 112.700816 -28.99791 -90)
		(property "Reference" "C858"
			(at -2.253996 -0.724408 90)
			(unlocked yes)
			(layer "F.SilkS")
			(effects
				(font
					(size 0.7874 0.5842)
					(thickness 0.1524)
				)
				(justify left)
			)
		)
		(property "Value" ""
			(at 0 0 270)
			(layer "F.Fab")
			(effects
				(font
					(size 1.27 1.27)
				)
			)
		)
		(duplicate_pad_numbers_are_jumpers no)
		(fp_line
			(start -1.905 0.8636)
			(end -1.905 -0.8636)
			(stroke
				(width 0.1524)
				(type default)
			)
			(layer "F.SilkS")
		)
		(fp_line
			(start 1.905 0.8636)
			(end -1.905 0.8636)
			(stroke
				(width 0.1524)
				(type default)
			)
			(layer "F.SilkS")
		)
		(fp_line
			(start 0 0.8382)
			(end 0 -0.8382)
			(stroke
				(width 0.1524)
				(type default)
			)
			(layer "F.SilkS")
		)
		(fp_line
			(start -1.905 -0.8636)
			(end 1.905 -0.8636)
			(stroke
				(width 0.1524)
				(type default)
			)
			(layer "F.SilkS")
		)
		(fp_line
			(start 1.905 -0.8636)
			(end 1.905 0.8636)
			(stroke
				(width 0.1524)
				(type default)
			)
			(layer "F.SilkS")
		)
		(fp_rect
			(start -1.524 0.7366)
			(end 1.524 -0.7366)
			(stroke
				(width 0)
				(type default)
			)
			(fill no)
			(layer "F.CrtYd")
		)
		(pad "1" smd rect
			(at 0.94996 0 270)
			(size 1.1176 1.3716)
			(layers "F.Cu" "F.Mask" "F.Paste")
			(net "PV_VTT_DDR_NODE1")
		)
		(pad "2" smd rect
			(at -0.94996 0 270)
			(size 1.1176 1.3716)
			(layers "F.Cu" "F.Mask" "F.Paste")
			(net "GND")
		)
	)
	(footprint ""
		(layer "F.Cu")
		(at 79.971392 -162.050222 90)
		(property "Reference" "C578"
			(at -2.815082 1.079754 90)
			(unlocked yes)
			(layer "F.SilkS")
			(effects
				(font
					(size 0.7874 0.5842)
					(thickness 0.1524)
				)
				(justify left)
			)
		)
		(property "Value" ""
			(at 0 0 90)
			(layer "F.Fab")
			(effects
				(font
					(size 1.27 1.27)
				)
			)
		)
		(duplicate_pad_numbers_are_jumpers no)
		(fp_line
			(start 0.7874 -0.4064)
			(end 0.7874 0.4064)
			(stroke
				(width 0.1524)
				(type default)
			)
			(layer "F.SilkS")
		)
		(fp_line
			(start -0.7874 -0.4064)
			(end 0.7874 -0.4064)
			(stroke
				(width 0.1524)
				(type default)
			)
			(layer "F.SilkS")
		)
		(fp_line
			(start 0 0.381)
			(end 0 -0.381)
			(stroke
				(width 0.1524)
				(type default)
			)
			(layer "F.SilkS")
		)
		(fp_line
			(start 0.7874 0.4064)
			(end -0.7874 0.4064)
			(stroke
				(width 0.1524)
				(type default)
			)
			(layer "F.SilkS")
		)
		(fp_line
			(start -0.7874 0.4064)
			(end -0.7874 -0.4064)
			(stroke
				(width 0.1524)
				(type default)
			)
			(layer "F.SilkS")
		)
		(fp_poly
			(pts
				(xy -0.5334 0.254) (xy -0.635 0.254) (xy -0.635 0.2286) (xy -0.635 -0.254) (xy -0.5334 -0.254) (xy -0.5334 -0.2794)
				(xy 0.5334 -0.2794) (xy 0.5334 -0.254) (xy 0.635 -0.254) (xy 0.635 0.254) (xy 0.5334 0.254) (xy 0.5334 0.2794)
				(xy -0.508 0.2794) (xy -0.5334 0.2794)
			)
			(stroke
				(width 0)
				(type default)
			)
			(fill no)
			(layer "F.CrtYd")
		)
		(pad "1" smd rect
			(at 0.40005 0 90)
			(size 0.4572 0.508)
			(layers "F.Cu" "F.Mask" "F.Paste")
			(net "P3V3_NODE1")
		)
		(pad "2" smd rect
			(at -0.40005 0 90)
			(size 0.4572 0.508)
			(layers "F.Cu" "F.Mask" "F.Paste")
			(net "GND")
		)
	)
	(footprint ""
		(layer "F.Cu")
		(at 140.27531 -111.507778 180)
		(property "Reference" "R20"
			(at -1.558036 -3.130804 0)
			(unlocked yes)
			(layer "F.SilkS")
			(effects
				(font
					(size 0.7874 0.5842)
					(thickness 0.1524)
				)
				(justify left)
			)
		)
		(property "Value" ""
			(at 0 0 180)
			(layer "F.Fab")
			(effects
				(font
					(size 1.27 1.27)
				)
			)
		)
		(duplicate_pad_numbers_are_jumpers no)
		(fp_line
			(start 0.7874 0.4064)
			(end -0.7874 0.4064)
			(stroke
				(width 0.1524)
				(type default)
			)
			(layer "F.SilkS")
		)
		(fp_line
			(start 0.7874 -0.4064)
			(end 0.7874 0.4064)
			(stroke
				(width 0.1524)
				(type default)
			)
			(layer "F.SilkS")
		)
		(fp_line
			(start -0.7874 0.4064)
			(end -0.7874 -0.4064)
			(stroke
				(width 0.1524)
				(type default)
			)
			(layer "F.SilkS")
		)
		(fp_line
			(start -0.7874 -0.4064)
			(end 0.7874 -0.4064)
			(stroke
				(width 0.1524)
				(type default)
			)
			(layer "F.SilkS")
		)
		(fp_poly
			(pts
				(xy -0.508 0.2794) (xy -0.508 0.2286) (xy -0.635 0.2286) (xy -0.635 -0.254) (xy -0.5334 -0.254)
				(xy -0.5334 -0.2794) (xy 0.5334 -0.2794) (xy 0.5334 -0.254) (xy 0.635 -0.254) (xy 0.635 0.254) (xy 0.5334 0.254)
				(xy 0.5334 0.2794)
			)
			(stroke
				(width 0)
				(type default)
			)
			(fill no)
			(layer "F.CrtYd")
		)
		(pad "1" smd rect
			(at 0.40005 0 180)
			(size 0.4572 0.508)
			(layers "F.Cu" "F.Mask" "F.Paste")
			(net "SEL_DOT_SRC5")
		)
		(pad "2" smd rect
			(at -0.40005 0 180)
			(size 0.4572 0.508)
			(layers "F.Cu" "F.Mask" "F.Paste")
			(net "P3V3_CLK_NODE1")
		)
	)
	(footprint ""
		(layer "F.Cu")
		(at 184.7596 -178.5112 180)
		(property "Reference" "R1316"
			(at -9.9822 -17.32407 0)
			(unlocked yes)
			(layer "F.SilkS")
			(effects
				(font
					(size 0.7874 0.5842)
					(thickness 0.1524)
				)
				(justify left)
			)
		)
		(property "Value" ""
			(at 0 0 180)
			(layer "F.Fab")
			(effects
				(font
					(size 1.27 1.27)
				)
			)
		)
		(duplicate_pad_numbers_are_jumpers no)
		(fp_line
			(start 0.7874 0.4064)
			(end -0.7874 0.4064)
			(stroke
				(width 0.1524)
				(type default)
			)
			(layer "F.SilkS")
		)
		(fp_line
			(start 0.7874 -0.4064)
			(end 0.7874 0.4064)
			(stroke
				(width 0.1524)
				(type default)
			)
			(layer "F.SilkS")
		)
		(fp_line
			(start -0.7874 0.4064)
			(end -0.7874 -0.4064)
			(stroke
				(width 0.1524)
				(type default)
			)
			(layer "F.SilkS")
		)
		(fp_line
			(start -0.7874 -0.4064)
			(end 0.7874 -0.4064)
			(stroke
				(width 0.1524)
				(type default)
			)
			(layer "F.SilkS")
		)
		(fp_poly
			(pts
				(xy -0.508 0.2794) (xy -0.508 0.2286) (xy -0.635 0.2286) (xy -0.635 -0.254) (xy -0.5334 -0.254)
				(xy -0.5334 -0.2794) (xy 0.5334 -0.2794) (xy 0.5334 -0.254) (xy 0.635 -0.254) (xy 0.635 0.254) (xy 0.5334 0.254)
				(xy 0.5334 0.2794)
			)
			(stroke
				(width 0)
				(type default)
			)
			(fill no)
			(layer "F.CrtYd")
		)
		(pad "1" smd rect
			(at 0.40005 0 180)
			(size 0.4572 0.508)
			(layers "F.Cu" "F.Mask" "F.Paste")
			(net "POWER_SW2_PWR_CTR_12V")
		)
		(pad "2" smd rect
			(at -0.40005 0 180)
			(size 0.4572 0.508)
			(layers "F.Cu" "F.Mask" "F.Paste")
			(net "POWER_SW2_PWR_CTR_12V_R")
		)
	)
)
